FILE_TYPE = CONNECTIVITY;
{Allegro Design Entry HDL 17.4-2019 S026 (4007227) 1/17/2022}
"PAGE_NUMBER" = 348;
0"NC";
1"GND\g";
2"GND\g";
3"GND\g";
4"P3V3_AUX\g";
5"P3V3_AUX\g";
6"GND\g";
7"GND\g";
8"I3C_SCM_3_R_SCL";
9"I3C_SCM_0_R_SCL";
10"I3C_SCM_0_R_SDA";
11"SMB_1_BMC_GPU_SCL";
12"PU_JTAG_DBP_BMC_PRDY_N"CDS_PHYS_NET_NAME"TP_JTAG_DBP_BMC_PRDY_N";
13"RST_MB_STBY_N";
14"SCM_ROT_CPU_RST_R_N";
15"P12V_SCM\g";
16"P12V_SCM\g";
17"SCM_VDD_RTC\g";
18"GND\g";
19"GND\g";
20"TP_CHASI";
21"SCM_SYS_PWROK_R1"CDS_PHYS_NET_NAME"SCM_SYS_PWROK_R";
22"SCM_SYS_PWRBTN_N"CDS_PHYS_NET_NAME"SCM_SYS_PWRBTN_N";
23"PWRGD_PS_PWROK"CDS_PHYS_NET_NAME"PWRGD_PS_PWROK";
24"SMB_HOST_CLK_3V3AUX_SDA";
25"P2E_CPU0_P5_RX_DN";
26"ESPI_CPU0_D1";
27"ESPI_CPU0_D0";
28"ESPI_CPU0_CS1_N";
29"CLK_ESPI_CPU0_CLK1";
30"FM_LPC_ESPI_SEL";
31"SGPIO_SCM_RESET_N";
32"SGPIO_SCM_RESET_R_N"CDS_PHYS_NET_NAME"SGPIO_SCM_RESET_R_N";
33"SGPIO_SCM_INTR_R1_N"CDS_PHYS_NET_NAME"SGPIO_SCM_INTR_R_N";
34"TP_SPI_2_PLD_CLK"CDS_PHYS_NET_NAME"TP_SPI_2_PLD_CLK";
35"TP_SPI_2_PLD_CS_N"CDS_PHYS_NET_NAME"TP_SPI_2_PLD_CS_N";
36"USB3_CPU0_BMC_RX_DN";
37"CLK_100M_BMC_RC_DN";
38"SCM_IRQ_N";
39"FM_UARTSW_LSB_N";
40"SCM_ROT_CPU_RST_R_N";
41"USB3_CPU0_BMC_RX_DP";
42"FM_SCM_PRSNT1_N";
43"SMB_PCIE2_3V3AUX_SCL_R0";
44"SMB_PCIE2_3V3AUX_SDA_R0";
45"RST_MB_STBY_R_N"CDS_PHYS_NET_NAME"RST_MB_STBY_R_N";
46"SCM_HDT_DBREQ_N"CDS_PHYS_NET_NAME"SCM_HDT_DBREQ_N";
47"FM_UARTSW_MSB_R";
48"IRQ0_A56";
49"FM_UARTSW_LSB_R";
50"SCM_ROT_CPU_RST_N";
51"FM_RST_PERST_SCM_N";
52"SCM_SYS_PWRBTN_R_N"CDS_PHYS_NET_NAME"SCM_SYS_PWRBTN_R_N";
53"TP_STBY_EN"CDS_PHYS_NET_NAME"TP_STBY_EN";
54"SMB_PCIE3_3V3AUX_SDA_R";
55"TP_PCIE_RXP[1]";
56"TP_PCIE_RXN[1]";
57"PWRGD_PS_PWROK_R"CDS_PHYS_NET_NAME"PWRGD_PS_PWROK_R";
58"SMB_HOST_CLK_3V3AUX_SDA_R0";
59"SMB_HOST_CLK_3V3AUX_SCL_R0";
60"FM_UARTSW_MSB_N";
61"FW_RECOVERY";
62"JTAG_SCM_DBREQ_N";
63"SGPIO_SCM_LD_<0>";
64"SGPIO_SCM_INTR_N";
65"SGPIO_SCM_DI_<0>";
66"FW_RECOVERY_R";
67"SMB_HOST_CLK_3V3AUX_SCL";
68"ESPI_CPU0_ALERT_N";
69"RST_ESPI_CPU0_RSTOUT_N";
70"ESPI_CPU0_D2";
71"ESPI_CPU0_D3";
72"SPI_CPU0_LVC3_SCM_CLK";
73"TP_SPI_2_PLD_IO0"CDS_PHYS_NET_NAME"TP_SPI_2_PLD_IO0";
74"FM_AC_PWR_BTN_N"CDS_PHYS_NET_NAME"TP_QSPI0_CS1_N";
75"SGPIO_SCM_DO_R_<1>"CDS_PHYS_NET_NAME"SGPIO_SCM_DO_R_<1>";
76"TP_SPI_2_PLD_IO2"CDS_PHYS_NET_NAME"TP_SPI_2_PLD_IO2";
77"USB2_HOST_BMC_B_DP";
78"USB2_HOST_BMC_B_DN";
79"USB2_CPU0_P1_DP";
80"USB2_CPU0_P1_DN";
81"TP_SPI_2_PLD_IO3"CDS_PHYS_NET_NAME"TP_SPI_2_PLD_IO3";
82"TP_SPI_2_PLD_IO1"CDS_PHYS_NET_NAME"TP_SPI_2_PLD_IO1";
83"SGPIO_SCM_CLK_R_<1>";
84"SGPIO_SCM_LD_R_<0>";
85"SGPIO_SCM_CLK_R_<0>";
86"SGPIO_SCM_LD_R_<1>";
87"SGPIO_SCM_DI_R_<1>";
88"SGPIO_SCM_DO_R_<0>";
89"SPI_CPU0_LVC3_SCM_D1";
90"SPI_CPU0_LVC3_SCM_D0";
91"FM_SOL_UART_CH_SEL_R";
92"RMII_OCP_BMC_RXD_0";
93"USB2_HUB_EXT_DN";
94"USB2_HUB_EXT_DP";
95"USB3_CPU0_BMC_TX_BUF_C_DP";
96"USB3_CPU0_BMC_TX_BUF_C_DN";
97"TP_PVCCIO_PECI_BMC";
98"TP_PECI_BMC";
99"RMII_OCP_BMC_RXD_1";
100"SPI_CPU0_LVC3_SCM_D3";
101"SPI_CPU0_LVC3_SCM_D2";
102"SPI_CPU0_LVC3_SCM_CS0_N";
103"SGPIO_SCM_DI_R_<0>";
104"RMII_BMC_OCP_TXD_1";
105"RMII_BMC_OCP_TX_EN"CDS_PHYS_NET_NAME"RMII_BMC_OCP_TX_EN";
106"FPGA_IO3V3_RSVD_1"CDS_PHYS_NET_NAME"TP_H_CPU_CATERR_LVC2_BMC_N";
107"SMB_1_BMC_GPU_SDA";
108"P2E_MB_BMC_RX_BUF_DN<0>";
109"CLK_100M_BMC_RC_DP";
110"P2E_MB_BMC_RX_BUF_DP<0>";
111"SMB_OCP_V3_2_3V3AUX_SDA_R0";
112"SMB_OCP_V3_2_3V3AUX_SCL_R0";
113"TP_PCIE_TXP[1]"CDS_PHYS_NET_NAME"TP_PCIE_TXP<1>";
114"P2E_MB_BMC_TX_C_DN<0>";
115"TP_PCIE_TXP[3]";
116"TP_BEEP_LED";
117"TP_PCIE_TXN[1]"CDS_PHYS_NET_NAME"TP_PCIE_TXN<1>";
118"P2E_MB_BMC_TX_C_DP<0>";
119"I3C_SCM_0_SDA"CDS_PHYS_NET_NAME"I3C_SCM_0_SDA";
120"I3C_SCM_1_SCL";
121"I3C_SCM_1_SDA";
122"I3C_SCM_2_SCL";
123"I3C_SCM_2_SDA";
124"SMB_OCP_SFF_3V3AUX_SDA";
125"SMB_CPU0_CPU1_APML_SCL";
126"SMB_VR_SENSOR_3V3AUX_SCL";
127"SMB_VR_SENSOR_3V3AUX_SDA";
128"SMB_CPU0_CPU1_SEC_SCL";
129"SMB_CPU0_CPU1_SEC_SDA";
130"SMB_FAN_3V3AUX_SCL";
131"SMB_1_PLD_3V3AUX_SDA_R3";
132"SMB_1_PLD_3V3AUX_SCL_R3";
133"SMB_PMBUS_3V3AUX_SDA_R0";
134"SMB_PMBUS_3V3AUX_SCL_R0";
135"SMB_1_PLD_3V3AUX_SCL";
136"SMB_PMBUS_3V3AUX_SDA";
137"SMB_PMBUS_3V3AUX_SCL";
138"SMB_OCP_V3_2_3V3AUX_SDA";
139"SMB_CPU0_CPU1_APML_SDA";
140"SMB_2_BMC_GPU_SCL";
141"I3C_BMC_SWB_SDA";
142"I3C_BMC_SWB_SCL";
143"SMB_CPU0_CPU1_SEC_SDA_R";
144"SMB_CPU0_CPU1_SEC_SCL_R";
145"SMB_VR_3V3AUX_SDA_R0";
146"SMB_OCP_SFF_3V3AUX_SCL";
147"SMB_OCP_V3_2_3V3AUX_SCL";
148"SMB_2_BMC_GPU_SDA";
149"SMB_1_PLD_3V3AUX_SDA";
150"I3C_SCM_3_R_SDA";
151"I3C_SCM_2_R_SDA";
152"I3C_SCM_2_R_SCL";
153"I3C_SCM_1_R_SDA";
154"I3C_SCM_1_R_SCL";
155"P2E_CPU0_P5_TX_C_DP";
156"CLK_100M_CPU0_CLK01_DN";
157"SMB_VR_3V3AUX_SCL_R0";
158"SMB_CPU0_CPU1_APML_SDA_R";
159"SMB_CPU0_CPU1_APML_SCL_R";
160"SMB_OCP_SFF_3V3AUX_SCL_R0";
161"VIRTUAL_RESEAT";
162"I3C_SCM_3_SDA";
163"I3C_SCM_3_SCL";
164"SMB_OCP_SFF_3V3AUX_SDA_R0";
165"I3C_SCM_0_SCL"CDS_PHYS_NET_NAME"I3C_SCM_0_SCL";
166"SGPIO_SCM_CLK_<0>";
167"SMB_PCIE3_3V3AUX_SCL_R";
168"SMB_PCIE0_3V3AUX_SDA";
169"SMB_PCIE0_3V3AUX_SCL";
170"P2E_CPU0_P5_RX_DP";
171"P2E_CPU0_P5_TX_C_DN";
172"CLK_100M_CPU0_CLK01_DP";
173"UART_CPU0_SCM_LVC3_UART1_TX";
174"LED_HDD_ACTIVITY_B_N";
175"JTAG_SCM_TDO_R";
176"FM_SOL_UART_CH_SEL";
177"UART_CPU0_SCM_LVC3_UART1_R_RX";
178"JTAG_SCM_TDI_R";
179"JTAG_SCM_TMS";
180"JTAG_SCM_TCK";
181"SMB_FAN_3V3AUX_SDA";
182"RMII_OCP_BMC_CRSDV"CDS_PHYS_NET_NAME"RMII_OCP_BMC_CRSDV";
183"RMII_BMC_OCP_TXD_0";
184"RMII_BMC_OCP_RX_ER"CDS_PHYS_NET_NAME"RMII_BMC_OCP_RX_ER";
185"CLK_50M_RMII_BMC_OCP"CDS_PHYS_NET_NAME"CLK_50M_RMII_BMC_OCP";
186"SPI_CPU0_LVC3_TPM_CS_N"CDS_PHYS_NET_NAME"SPI_CPU0_LVC3_TPM_CS_N";
187"PRSNT0_N";
188"UART_BMC_BIC_TX"CDS_PHYS_NET_NAME"UART_BMC_BIC_TX";
189"UART_BMC_BIC_BUF_RX"CDS_PHYS_NET_NAME"UART_BMC_BIC_BUF_RX";
190"UART_CPU0_SCM_LVC3_UART1_RX"CDS_PHYS_NET_NAME"TP_UART_CPU0_SCM_LVC3_UART1_RX";
191"UART_CPU0_SCM_LVC3_UART1_R1_TX"CDS_PHYS_NET_NAME"TP_UART_CPU0_SCM_LVC3_UART1_TX";
192"RST_SRST_PLD_BMC_N"CDS_PHYS_NET_NAME"TP_SPI_TPM_CLK";
193"FM_AC_PWR_BTN_R_N";
194"SGPIO_SCM_LD_<1>";
195"SGPIO_SCM_DO_<0>";
196"SGPIO_SCM_DO_<1>";
197"SGPIO_SCM_CLK_<1>";
198"SGPIO_SCM_DI_<1>";
%"Q_RES"
"1","(-14925,8425)","0","pure_quanta","I101";
;
LOCATION"R2422"
$SEC"1"
CDS_SEC"1"
VALUE"33.2"
TOLERANCE"1%"
MATERIAL"CHIP"
CDS_LIB"pure_quanta"
PACK_TYPE"0402LF"
WATTAGE"1/16W"
PART_NUMBER"CS03322FB03";
"B"
$PN"2"145;
"A"
$PN"1"127;
%"Q_RES"
"1","(-14925,8625)","0","pure_quanta","I102";
;
LOCATION"R3239"
$SEC"1"
CDS_SEC"1"
MATERIAL"CHIP"
VALUE"33.2"
TOLERANCE"1%"
CDS_LIB"pure_quanta"
WATTAGE"1/16W"
PACK_TYPE"0402LF"
PART_NUMBER"CS03322FB03";
"B"
$PN"2"164;
"A"
$PN"1"124;
%"Q_RES"
"1","(-14925,8675)","0","pure_quanta","I103";
;
LOCATION"R3238"
$SEC"1"
CDS_SEC"1"
VALUE"33.2"
MATERIAL"CHIP"
TOLERANCE"1%"
CDS_LIB"pure_quanta"
WATTAGE"1/16W"
PACK_TYPE"0402LF"
PART_NUMBER"CS03322FB03";
"B"
$PN"2"160;
"A"
$PN"1"146;
%"Q_RES"
"1","(-14925,8575)","0","pure_quanta","I104";
;
LOCATION"R2419"
$SEC"1"
CDS_SEC"1"
PACK_TYPE"0402LF"
WATTAGE"1/16W"
VALUE"33.2"
MATERIAL"CHIP"
TOLERANCE"1%"
CDS_LIB"pure_quanta"
PART_NUMBER"CS03322FB03";
"B"
$PN"2"159;
"A"
$PN"1"125;
%"Q_RES"
"1","(-14925,8525)","0","pure_quanta","I105";
;
LOCATION"R2420"
$SEC"1"
CDS_SEC"1"
MATERIAL"CHIP"
TOLERANCE"1%"
VALUE"33.2"
WATTAGE"1/16W"
PACK_TYPE"0402LF"
CDS_LIB"pure_quanta"
PART_NUMBER"CS03322FB03";
"B"
$PN"2"158;
"A"
$PN"1"139;
%"Q_RES"
"1","(-14425,8975)","2","pure_quanta","I117";
;
LOCATION"R6006"
$SEC"1"
CDS_SEC"1"
VALUE"0"
CDS_LIB"pure_quanta"
BOM_COST"MEM"
WATTAGE"1/16W"
MATERIAL"CHIP"
TOLERANCE"5%"
PACK_TYPE"0402LF"
PART_NUMBER"CS00002JB13";
"B"
$PN"2"8;
"A"
$PN"1"163;
%"Q_RES"
"1","(-14425,9025)","2","pure_quanta","I118";
;
LOCATION"R6005"
$SEC"1"
CDS_SEC"1"
VALUE"0"
PACK_TYPE"0402LF"
TOLERANCE"5%"
MATERIAL"CHIP"
WATTAGE"1/16W"
BOM_COST"MEM"
CDS_LIB"pure_quanta"
PART_NUMBER"CS00002JB13";
"B"
$PN"2"151;
"A"
$PN"1"123;
%"Q_RES"
"1","(-14425,8925)","2","pure_quanta","I119";
;
LOCATION"R6007"
$SEC"1"
CDS_SEC"1"
VALUE"0"
CDS_LIB"pure_quanta"
BOM_COST"MEM"
WATTAGE"1/16W"
MATERIAL"CHIP"
TOLERANCE"5%"
PACK_TYPE"0402LF"
PART_NUMBER"CS00002JB13";
"B"
$PN"2"150;
"A"
$PN"1"162;
%"Q_RES"
"1","(-14425,9075)","2","pure_quanta","I120";
;
LOCATION"R6004"
$SEC"1"
CDS_SEC"1"
VALUE"0"
PACK_TYPE"0402LF"
TOLERANCE"5%"
MATERIAL"CHIP"
WATTAGE"1/16W"
BOM_COST"MEM"
CDS_LIB"pure_quanta"
PART_NUMBER"CS00002JB13";
"B"
$PN"2"152;
"A"
$PN"1"122;
%"Q_RES"
"1","(-14425,9125)","2","pure_quanta","I121";
;
LOCATION"R6003"
$SEC"1"
CDS_SEC"1"
VALUE"0"
PACK_TYPE"0402LF"
TOLERANCE"5%"
MATERIAL"CHIP"
WATTAGE"1/16W"
BOM_COST"MEM"
CDS_LIB"pure_quanta"
PART_NUMBER"CS00002JB13";
"B"
$PN"2"153;
"A"
$PN"1"121;
%"Q_RES"
"1","(-14425,9175)","2","pure_quanta","I122";
;
LOCATION"R6002"
$SEC"1"
CDS_SEC"1"
VALUE"0"
PACK_TYPE"0402LF"
TOLERANCE"5%"
MATERIAL"CHIP"
WATTAGE"1/16W"
BOM_COST"MEM"
CDS_LIB"pure_quanta"
PART_NUMBER"CS00002JB13";
"B"
$PN"2"154;
"A"
$PN"1"120;
%"Q_RES"
"1","(-14425,9275)","2","pure_quanta","I123";
;
LOCATION"R6000"
$SEC"1"
CDS_SEC"1"
VALUE"0"
PACK_TYPE"0402LF"
TOLERANCE"5%"
MATERIAL"CHIP"
WATTAGE"1/16W"
BOM_COST"MEM"
CDS_LIB"pure_quanta"
PART_NUMBER"CS00002JB13";
"B"
$PN"2"9;
"A"
$PN"1"165;
%"Q_RES"
"1","(-14425,9225)","2","pure_quanta","I124";
;
LOCATION"R6001"
$SEC"1"
CDS_SEC"1"
VALUE"0"
PACK_TYPE"0402LF"
TOLERANCE"5%"
MATERIAL"CHIP"
WATTAGE"1/16W"
BOM_COST"MEM"
CDS_LIB"pure_quanta"
PART_NUMBER"CS00002JB13";
"B"
$PN"2"10;
"A"
$PN"1"119;
%"UNIVERSAL_POWER"
"1","(-12925,9750)","0","pure_quanta_power","I126";
;
HDL_POWER"P12V_SCM"
CDS_LIB"pure_quanta_power";
"A"15;
%"UNIVERSAL_POWER"
"1","(-11200,9750)","0","pure_quanta_power","I127";
;
HDL_POWER"P12V_SCM"
CDS_LIB"pure_quanta_power";
"A"16;
%"Q_RES"
"1","(-10300,6825)","2","pure_quanta","I128";
;
LOCATION"R6014"
$SEC"1"
CDS_SEC"1"
VALUE"0"
CDS_LIB"pure_quanta"
BOM_COST"MEM"
WATTAGE"1/16W"
MATERIAL"CHIP"
TOLERANCE"5%"
PACK_TYPE"0402LF"
PART_NUMBER"CS00002JB13";
"B"
$PN"2"87;
"A"
$PN"1"198;
%"Q_RES"
"1","(-10300,6775)","2","pure_quanta","I129";
;
LOCATION"R6015"
$SEC"1"
CDS_SEC"1"
VALUE"0"
CDS_LIB"pure_quanta"
BOM_COST"MEM"
WATTAGE"1/16W"
MATERIAL"CHIP"
TOLERANCE"5%"
PACK_TYPE"0402LF"
PART_NUMBER"CS00002JB13";
"B"
$PN"2"86;
"A"
$PN"1"194;
%"Q_RES"
"1","(-10300,6875)","2","pure_quanta","I130";
;
LOCATION"R6013"
$SEC"1"
CDS_SEC"1"
VALUE"0"
PACK_TYPE"0402LF"
TOLERANCE"5%"
MATERIAL"CHIP"
WATTAGE"1/16W"
BOM_COST"MEM"
CDS_LIB"pure_quanta"
PART_NUMBER"CS00002JB13";
"B"
$PN"2"83;
"A"
$PN"1"197;
%"Q_RES"
"1","(-10300,6925)","2","pure_quanta","I131";
;
LOCATION"R6012"
$SEC"1"
CDS_SEC"1"
VALUE"0"
CDS_LIB"pure_quanta"
BOM_COST"MEM"
WATTAGE"1/16W"
MATERIAL"CHIP"
TOLERANCE"5%"
PACK_TYPE"0402LF"
PART_NUMBER"CS00002JB13";
"B"
$PN"2"75;
"A"
$PN"1"196;
%"Q_RES"
"1","(-10300,7025)","2","pure_quanta","I132";
;
LOCATION"R6011"
$SEC"1"
CDS_SEC"1"
VALUE"0"
PACK_TYPE"0402LF"
TOLERANCE"5%"
MATERIAL"CHIP"
WATTAGE"1/16W"
BOM_COST"MEM"
CDS_LIB"pure_quanta"
PART_NUMBER"CS00002JB13";
"B"
$PN"2"84;
"A"
$PN"1"63;
%"Q_RES"
"1","(-10300,7075)","2","pure_quanta","I133";
;
LOCATION"R6010"
$SEC"1"
CDS_SEC"1"
VALUE"0"
CDS_LIB"pure_quanta"
BOM_COST"MEM"
WATTAGE"1/16W"
MATERIAL"CHIP"
TOLERANCE"5%"
PACK_TYPE"0402LF"
PART_NUMBER"CS00002JB13";
"B"
$PN"2"103;
"A"
$PN"1"65;
%"Q_RES"
"1","(-10300,7125)","2","pure_quanta","I134";
;
LOCATION"R6009"
$SEC"1"
CDS_SEC"1"
VALUE"0"
CDS_LIB"pure_quanta"
BOM_COST"MEM"
WATTAGE"1/16W"
MATERIAL"CHIP"
TOLERANCE"5%"
PACK_TYPE"0402LF"
PART_NUMBER"CS00002JB13";
"B"
$PN"2"85;
"A"
$PN"1"166;
%"Q_RES"
"1","(-10300,7175)","2","pure_quanta","I135";
;
LOCATION"R6008"
$SEC"1"
CDS_SEC"1"
VALUE"0"
PACK_TYPE"0402LF"
TOLERANCE"5%"
MATERIAL"CHIP"
WATTAGE"1/16W"
BOM_COST"MEM"
CDS_LIB"pure_quanta"
PART_NUMBER"CS00002JB13";
"B"
$PN"2"88;
"A"
$PN"1"195;
%"UNIVERSAL_GND"
"1","(-15200,3950)","0","pure_quanta_power","I16";
;
CDS_LIB"pure_quanta_power"
HDL_POWER"GND";
"A"1;
%"Q_RES"
"1","(-9450,8825)","0","pure_quanta","I169";
;
LOCATION"R3778"
$SEC"1"
CDS_SEC"1"
MATERIAL"CHIP"
VALUE"0"
CDS_LIB"pure_quanta"
PACK_TYPE"0402LF"
TOLERANCE"5%"
WATTAGE"1/16W"
PART_NUMBER"CS00002JB13";
"B"
$PN"2"176;
"A"
$PN"1"91;
%"Q_RES"
"2","(-15200,4200)","0","pure_quanta","I17";
;
LOCATION"R6035"
$SEC"1"
CDS_SEC"1"
PACK_TYPE"0402LF"
MATERIAL"EMPTY"
WATTAGE"1/16W"
TOLERANCE"5%"
VALUE"4.7K"
CDS_LIB"pure_quanta"
PART_NUMBER"CS24702JB10";
"A"
$PN"1"14;
"B"
$PN"2"1;
%"UNIVERSAL_GND"
"1","(-9275,9350)","0","pure_quanta_power","I170";
;
CDS_LIB"pure_quanta_power"
HDL_POWER"GND";
"A"2;
%"Q_RES"
"2","(-9275,9550)","0","pure_quanta","I171";
;
LOCATION"R1801"
$SEC"1"
CDS_SEC"1"
VALUE"0"
TOLERANCE"5%"
WATTAGE"1/16W"
MATERIAL"CHIP"
PACK_TYPE"0402LF"
CDS_LIB"pure_quanta"
PART_NUMBER"CS00002JB13";
"A"
$PN"1"187;
"B"
$PN"2"2;
%"VCC_CORE"
"1","(-8700,6950)","0","pure_quanta_power","I172";
;
HDL_POWER"SCM_VDD_RTC"
CDS_LIB"pure_quanta_power";
"A"17;
%"UNIVERSAL_GND"
"1","(-8450,8250)","0","pure_quanta_power","I173";
;
CDS_LIB"pure_quanta_power"
HDL_POWER"GND";
"A"3;
%"Q_RES"
"2","(-8450,8475)","0","pure_quanta","I174";
;
LOCATION"R6028"
$SEC"1"
CDS_SEC"1"
TOLERANCE"5%"
MATERIAL"CHIP"
PACK_TYPE"0402LF"
VALUE"0"
WATTAGE"1/16W"
CDS_LIB"pure_quanta"
PART_NUMBER"CS00002JB13";
"A"
$PN"1"30;
"B"
$PN"2"3;
%"SCONN168_ME1016810202011"
"1","(-12050,7100)","2","pure_quanta","I176";
;
LOCATION"J41"
SEC"1"
PART_TYPE"SMLF"
VALUE"SCONN168_ME1016810202011"
MATERIAL"IO"
CDS_LIB"pure_quanta"
NEEDS_NO_SIZE"TRUE"
CDS_LMAN_SYM_OUTLINE"-500,2475,500,-2475"
SEC_TYPE""
PART_NUMBER"DFHSG8FR011";
"G5"
$PN"G5"18;
"G4"
$PN"G4"18;
"G3"
$PN"G3"18;
"G2"
$PN"G2"18;
"G1"
$PN"G1"18;
"PRSNTB3# \B"
$PN"B70"19;
"RFU1_NC_B69"
$PN"B69"116;
"RFU1_NC_B68"
$PN"B68"115;
"GND_B67"
$PN"B67"19;
"PETP15"
$PN"B66"114;
"PETN15"
$PN"B65"118;
"GND_B64"
$PN"B64"19;
"PETP14"
$PN"B63"117;
"PETN14"
$PN"B62"113;
"GND_B61"
$PN"B61"19;
"PETP13"
$PN"B60"96;
"PETN13"
$PN"B59"95;
"GND_B58"
$PN"B58"19;
"PETP12"
$PN"B57"93;
"PWRBRK0# \B"
$PN"A70"18;
"USB_DATP"
$PN"A69"37;
"USB_DATN"
$PN"A68"109;
"GND_A67"
$PN"A67"18;
"PERP15"
$PN"A66"108;
"PERN15"
$PN"A65"110;
"GND_A64"
$PN"A64"18;
"PERP14"
$PN"A63"56;
"PERN14"
$PN"A62"55;
"GND_A61"
$PN"A61"18;
"PERP13"
$PN"A60"36;
"PERN13"
$PN"A59"41;
"GND_A58"
$PN"A58"18;
"PERP12"
$PN"A57"42;
"PERN12"
$PN"A56"48;
"GND_A55"
$PN"A55"49;
"PERP11"
$PN"A54"20;
"PERN11"
$PN"A53"50;
"GND_A52"
$PN"A52"47;
"PERP10"
$PN"A51"51;
"PERN10"
$PN"A50"12;
"GND_A49"
$PN"A49"46;
"PERP9"
$PN"A48"21;
"PERN9"
$PN"A47"52;
"GND_A46"
$PN"A46"45;
"PERP8"
$PN"A45"53;
"PERN8"
$PN"A44"57;
"GND_A43"
$PN"A43"61;
"PRSNTB1# \B"
$PN"A42"18;
"GND_A41"
$PN"A41"58;
"PERP7"
$PN"A40"59;
"PERN7"
$PN"A39"54;
"GND_A38"
$PN"A38"167;
"PERP6"
$PN"A37"175;
"PERN6"
$PN"A36"178;
"GND_A35"
$PN"A35"179;
"PERP5"
$PN"A34"180;
"PERN5"
$PN"A33"18;
"GND_A32"
$PN"A32"44;
"PERP4"
$PN"A31"43;
"PERN4"
$PN"A30"181;
"GND_A29"
$PN"A29"130;
"GND_A28"
$PN"A28"131;
"PERP3"
$PN"A27"132;
"PERN3"
$PN"A26"133;
"GND_A25"
$PN"A25"134;
"PERP2"
$PN"A24"168;
"PERN2"
$PN"A23"169;
"GND_A22"
$PN"A22"18;
"PERP1"
$PN"A21"25;
"PERN1"
$PN"A20"170;
"GND_A19"
$PN"A19"18;
"PERP0"
$PN"A18"171;
"PERN0"
$PN"A17"155;
"GND_A16"
$PN"A16"18;
"REFCLKP1"
$PN"A15"156;
"REFCLKN1"
$PN"A14"172;
"GND_A13"
$PN"A13"18;
"PRSNTB2# \B"
$PN"A12"111;
"PERST1# \B"
$PN"A11"112;
"PRSNTA# \B"
$PN"A10"141;
"SMRST# \B"
$PN"A9"142;
"SMDAT"
$PN"A8"143;
"SMCLK"
$PN"A7"144;
"GND_A6"
$PN"A6"145;
"GND_A5"
$PN"A5"157;
"GND_A4"
$PN"A4"158;
"GND_A3"
$PN"A3"159;
"GND_A2"
$PN"A2"164;
"GND_A1"
$PN"A1"160;
"RBT_CLK_IN"
$PN"OA14"161;
"GND_OA13"
$PN"OA13"18;
"REFCLKP3"
$PN"OA12"162;
"REFCLKN3"
$PN"OA11"163;
"GND_OA10"
$PN"OA10"123;
"RBT_TXD0"
$PN"OA9"122;
"RBT_TXD1"
$PN"OA8"121;
"RBT_TX_EN"
$PN"OA7"120;
"SLOT_ID1"
$PN"OA6"119;
"RBT_ARB_OUT"
$PN"OA5"165;
"RBT_ARB_IN"
$PN"OA4"18;
"WAKE# \B"
$PN"OA3"18;
"PERST3# \B"
$PN"OA2"15;
"PERST2# \B"
$PN"OA1"15;
"PETN12"
$PN"B56"94;
"GND_B55"
$PN"B55"19;
"PETP11"
$PN"B54"80;
"PETN11"
$PN"B53"79;
"GND_B52"
$PN"B52"19;
"PETP10"
$PN"B51"78;
"PETN10"
$PN"B50"77;
"GND_B49"
$PN"B49"19;
"PETP9"
$PN"B48"81;
"PETN9"
$PN"B47"76;
"GND_B46"
$PN"B46"82;
"PETP8"
$PN"B45"73;
"PETN8"
$PN"B44"35;
"GND_B43"
$PN"B43"34;
"PRSNTB0# \B"
$PN"B42"74;
"GND_B41"
$PN"B41"17;
"PETP7"
$PN"B40"33;
"PETN7"
$PN"B39"32;
"GND_B38"
$PN"B38"19;
"PETP6"
$PN"B37"86;
"PETN6"
$PN"B36"87;
"GND_B35"
$PN"B35"83;
"PETP5"
$PN"B34"75;
"PETN5"
$PN"B33"19;
"GND_B32"
$PN"B32"84;
"PETP4"
$PN"B31"103;
"PETN4"
$PN"B30"85;
"GND_B29"
$PN"B29"88;
"GND_B28"
$PN"B28"97;
"PETP3"
$PN"B27"98;
"PETN3"
$PN"B26"19;
"GND_B25"
$PN"B25"99;
"PETP2"
$PN"B24"92;
"PETN2"
$PN"B23"184;
"GND_B22"
$PN"B22"104;
"PETP1"
$PN"B21"183;
"PETN1"
$PN"B20"105;
"GND_B19"
$PN"B19"182;
"PETP0"
$PN"B18"185;
"PETN0"
$PN"B17"19;
"GND_B16"
$PN"B16"100;
"REFCLKP0"
$PN"B15"101;
"REFCLKN0"
$PN"B14"89;
"GND_B13"
$PN"B13"90;
"AUX_PWR_EN"
$PN"B12"102;
"+3.3V_EDGE"
$PN"B11"72;
"PERST0# \B"
$PN"B10"19;
"BIF2# \B"
$PN"B9"30;
"BIF1# \B"
$PN"B8"71;
"BIF0# \B"
$PN"B7"70;
"+12V_EDGE_B6"
$PN"B6"26;
"+12V_EDGE_B5"
$PN"B5"27;
"+12V_EDGE_B4"
$PN"B4"69;
"+12V_EDGE_B3"
$PN"B3"68;
"+12V_EDGE_B2"
$PN"B2"28;
"+12V_EDGE_B1"
$PN"B1"29;
"RBT_CRS_DV"
$PN"OB14"91;
"GND_OB13"
$PN"OB13"106;
"REFCLKP2"
$PN"OB12"186;
"REFCLKN2"
$PN"OB11"192;
"GND_OB10"
$PN"OB10"19;
"RBT_RXD0"
$PN"OB9"191;
"RBT_RXD1"
$PN"OB8"190;
"SLOT_ID0"
$PN"OB7"19;
"CLK"
$PN"OB6"189;
"DATA_OUT"
$PN"OB5"188;
"DATA_IN"
$PN"OB4"19;
"LD# \B"
$PN"OB3"187;
"MAIN_PWR_EN"
$PN"OB2"16;
"NIC_PWR_GOOD"
$PN"OB1"16;
%"Q_RES"
"1","(-9825,9125)","0","pure_quanta","I177";
;
LOCATION"R6064"
$SEC"1"
CDS_SEC"1"
MATERIAL"EMPTY"
VALUE"0"
WATTAGE"1/16W"
TOLERANCE"5%"
PACK_TYPE"0402LF"
CDS_LIB"pure_quanta"
PART_NUMBER"CS00002JB13";
"B"
$PN"2"177;
"A"
$PN"1"190;
%"Q_RES"
"1","(-9825,9075)","0","pure_quanta","I178";
;
LOCATION"R6065"
$SEC"1"
CDS_SEC"1"
MATERIAL"EMPTY"
VALUE"0"
CDS_LIB"pure_quanta"
PACK_TYPE"0402LF"
TOLERANCE"5%"
WATTAGE"1/16W"
PART_NUMBER"CS00002JB13";
"B"
$PN"2"173;
"A"
$PN"1"191;
%"Q_RES"
"2","(-15200,4700)","0","pure_quanta","I18";
;
LOCATION"R6034"
$SEC"1"
CDS_SEC"1"
PACK_TYPE"0402LF"
MATERIAL"CHIP"
WATTAGE"1/16W"
VALUE"1K"
TOLERANCE"1%"
CDS_LIB"pure_quanta"
PART_NUMBER"CS21002FB06";
"A"
$PN"1"5;
"B"
$PN"2"14;
%"VCC_CORE"
"1","(-16775,6600)","0","pure_quanta_power","I182";
;
HDL_POWER"P3V3_AUX"
CDS_LIB"pure_quanta_power";
"A"4;
%"UNIVERSAL_POWER"
"1","(-15200,4975)","0","pure_quanta_power","I19";
;
HDL_POWER"P3V3_AUX"
CDS_LIB"pure_quanta_power";
"A"5;
%"Q_RES"
"1","(-14925,8325)","0","pure_quanta","I190";
;
LOCATION"R4507"
$SEC"1"
CDS_SEC"1"
MATERIAL"CHIP"
TOLERANCE"1%"
VALUE"33.2"
WATTAGE"1/16W"
PACK_TYPE"0402LF"
CDS_LIB"pure_quanta"
PART_NUMBER"CS03322FB03";
"B"
$PN"2"143;
"A"
$PN"1"129;
%"Q_RES"
"1","(-14925,8375)","0","pure_quanta","I191";
;
LOCATION"R4506"
$SEC"1"
CDS_SEC"1"
MATERIAL"CHIP"
TOLERANCE"1%"
VALUE"33.2"
WATTAGE"1/16W"
PACK_TYPE"0402LF"
CDS_LIB"pure_quanta"
PART_NUMBER"CS03322FB03";
"B"
$PN"2"144;
"A"
$PN"1"128;
%"Q_RES"
"1","(-14925,7425)","0","pure_quanta","I195";
;
LOCATION"R2424"
$SEC"1"
CDS_SEC"1"
MATERIAL"CHIP"
TOLERANCE"1%"
VALUE"33.2"
PACK_TYPE"0402LF"
WATTAGE"1/16W"
CDS_LIB"pure_quanta"
PART_NUMBER"CS03322FB03";
"B"
$PN"2"133;
"A"
$PN"1"136;
%"Q_RES"
"1","(-14925,7475)","0","pure_quanta","I196";
;
LOCATION"R2423"
$SEC"1"
CDS_SEC"1"
VALUE"33.2"
TOLERANCE"1%"
MATERIAL"CHIP"
PACK_TYPE"0402LF"
WATTAGE"1/16W"
CDS_LIB"pure_quanta"
PART_NUMBER"CS03322FB03";
"B"
$PN"2"134;
"A"
$PN"1"137;
%"Q_RES"
"2","(-16775,6350)","2","pure_quanta","I214";
;
LOCATION"R6071"
$SEC"1"
CDS_SEC"1"
PACK_TYPE"0402LF"
MATERIAL"EMPTY"
VALUE"4.7K"
WATTAGE"1/16W"
TOLERANCE"5%"
CDS_LIB"pure_quanta"
PART_NUMBER"CS24702JB10";
"A"
$PN"1"4;
"B"
$PN"2"12;
%"Q_RES"
"1","(-10300,6525)","2","pure_quanta","I215";
;
LOCATION"R8101"
$SEC"1"
CDS_SEC"1"
VALUE"0"
BOM_COST"MEM"
WATTAGE"1/16W"
MATERIAL"CHIP"
TOLERANCE"5%"
PACK_TYPE"0402LF"
CDS_LIB"pure_quanta"
PART_NUMBER"CS00002JB13";
"B"
$PN"2"74;
"A"
$PN"1"193;
%"Q_CAP"
"1","(-8500,6675)","0","pure_quanta","I219";
;
LOCATION"C6000"
$SEC"1"
CDS_SEC"1"
PACK_TYPE"0402"
TOLERANCE"10%"
VALUE"0.1UF"
MATERIAL"X7R"
VOLTAGE"25V"
CDS_LIB"pure_quanta"
PART_NUMBER"CH4104K1B00";
"B"
$PN"2"7;
"A"
$PN"1"17;
%"Q_RES"
"2","(-16725,5525)","0","pure_quanta","I220";
;
LOCATION"R4809"
$SEC"1"
CDS_SEC"1"
VALUE"0"
TOLERANCE"5%"
MATERIAL"CHIP"
WATTAGE"1/16W"
PACK_TYPE"0402LF"
CDS_LIB"pure_quanta"
PART_NUMBER"CS00002JB13";
"A"
$PN"1"20;
"B"
$PN"2"6;
%"UNIVERSAL_GND"
"1","(-16725,5225)","0","pure_quanta_power","I221";
;
CDS_LIB"pure_quanta_power"
HDL_POWER"GND";
"A"6;
%"Q_RES"
"1","(-14975,5725)","0","pure_quanta","I24";
;
LOCATION"R321"
$SEC"1"
CDS_SEC"1"
MATERIAL"CHIP"
TOLERANCE"5%"
VALUE"0"
PACK_TYPE"0402LF"
WATTAGE"1/16W"
CDS_LIB"pure_quanta"
PART_NUMBER"CS00002JB13";
"B"
$PN"2"48;
"A"
$PN"1"38;
%"Q_RES"
"1","(-14975,5775)","0","pure_quanta","I25";
;
LOCATION"R3777"
$SEC"1"
CDS_SEC"1"
MATERIAL"CHIP"
TOLERANCE"5%"
VALUE"0"
WATTAGE"1/16W"
PACK_TYPE"0402LF"
CDS_LIB"pure_quanta"
PART_NUMBER"CS00002JB13";
"B"
$PN"2"49;
"A"
$PN"1"39;
%"Q_RES"
"1","(-14975,5875)","0","pure_quanta","I26";
;
LOCATION"R1798"
$SEC"1"
CDS_SEC"1"
MATERIAL"CHIP"
TOLERANCE"5%"
VALUE"0"
PACK_TYPE"0402LF"
WATTAGE"1/16W"
CDS_LIB"pure_quanta"
PART_NUMBER"CS00002JB13";
"B"
$PN"2"50;
"A"
$PN"1"40;
%"Q_RES"
"1","(-14975,5925)","0","pure_quanta","I27";
;
LOCATION"R3776"
$SEC"1"
CDS_SEC"1"
MATERIAL"CHIP"
TOLERANCE"5%"
VALUE"0"
PACK_TYPE"0402LF"
WATTAGE"1/16W"
CDS_LIB"pure_quanta"
PART_NUMBER"CS00002JB13";
"B"
$PN"2"47;
"A"
$PN"1"60;
%"Q_RES"
"1","(-14950,6075)","0","pure_quanta","I28";
;
LOCATION"R6032"
$SEC"1"
CDS_SEC"1"
TOLERANCE"5%"
VALUE"0"
MATERIAL"CHIP"
PACK_TYPE"0402LF"
WATTAGE"1/16W"
CDS_LIB"pure_quanta"
PART_NUMBER"CS00002JB13";
"B"
$PN"2"46;
"A"
$PN"1"62;
%"Q_RES"
"1","(-14950,6175)","0","pure_quanta","I29";
;
LOCATION"R1815"
$SEC"1"
CDS_SEC"1"
VALUE"0"
TOLERANCE"5%"
MATERIAL"CHIP"
PACK_TYPE"0402LF"
WATTAGE"1/16W"
CDS_LIB"pure_quanta"
PART_NUMBER"CS00002JB13";
"B"
$PN"2"52;
"A"
$PN"1"22;
%"Q_RES"
"1","(-14950,6225)","0","pure_quanta","I30";
;
LOCATION"R6033"
$SEC"1"
CDS_SEC"1"
VALUE"0"
TOLERANCE"5%"
MATERIAL"CHIP"
CDS_LIB"pure_quanta"
WATTAGE"1/16W"
PACK_TYPE"0402LF"
PART_NUMBER"CS00002JB13";
"B"
$PN"2"45;
"A"
$PN"1"13;
%"Q_RES"
"1","(-14950,6375)","0","pure_quanta","I31";
;
LOCATION"R4087"
$SEC"1"
CDS_SEC"1"
VALUE"0"
TOLERANCE"5%"
MATERIAL"CHIP"
CDS_LIB"pure_quanta"
PACK_TYPE"0402LF"
WATTAGE"1/16W"
PART_NUMBER"CS00002JB13";
"B"
$PN"2"61;
"A"
$PN"1"66;
%"Q_RES"
"1","(-14950,6325)","0","pure_quanta","I32";
;
LOCATION"R1816"
$SEC"1"
CDS_SEC"1"
VALUE"0"
MATERIAL"CHIP"
TOLERANCE"5%"
WATTAGE"1/16W"
PACK_TYPE"0402LF"
CDS_LIB"pure_quanta"
PART_NUMBER"CS00002JB13";
"B"
$PN"2"57;
"A"
$PN"1"23;
%"Q_RES"
"1","(-14950,6675)","0","pure_quanta","I33";
;
LOCATION"R2416"
$SEC"1"
CDS_SEC"1"
VALUE"33.2"
MATERIAL"CHIP"
TOLERANCE"1%"
WATTAGE"1/16W"
PACK_TYPE"0402LF"
CDS_LIB"pure_quanta"
PART_NUMBER"CS03322FB03";
"B"
$PN"2"54;
"A"
$PN"1"107;
%"Q_RES"
"1","(-14950,6575)","0","pure_quanta","I34";
;
LOCATION"R2418"
$SEC"1"
CDS_SEC"1"
MATERIAL"CHIP"
VALUE"33.2"
TOLERANCE"1%"
CDS_LIB"pure_quanta"
PACK_TYPE"0402LF"
WATTAGE"1/16W"
PART_NUMBER"CS03322FB03";
"B"
$PN"2"58;
"A"
$PN"1"24;
%"Q_RES"
"1","(-14950,6625)","0","pure_quanta","I35";
;
LOCATION"R2417"
$SEC"1"
CDS_SEC"1"
TOLERANCE"1%"
VALUE"33.2"
MATERIAL"CHIP"
CDS_LIB"pure_quanta"
PACK_TYPE"0402LF"
WATTAGE"1/16W"
PART_NUMBER"CS03322FB03";
"B"
$PN"2"59;
"A"
$PN"1"67;
%"UNIVERSAL_GND"
"1","(-12925,4625)","0","pure_quanta_power","I40";
;
CDS_LIB"pure_quanta_power"
HDL_POWER"GND";
"A"18;
%"UNIVERSAL_GND"
"1","(-11200,4700)","0","pure_quanta_power","I41";
;
CDS_LIB"pure_quanta_power"
HDL_POWER"GND";
"A"19;
%"Q_RES"
"1","(-10300,6625)","2","pure_quanta","I42";
;
LOCATION"R6026"
$SEC"1"
CDS_SEC"1"
VALUE"0"
CDS_LIB"pure_quanta"
BOM_COST"MEM"
WATTAGE"1/16W"
MATERIAL"CHIP"
TOLERANCE"5%"
PACK_TYPE"0402LF"
PART_NUMBER"CS00002JB13";
"B"
$PN"2"33;
"A"
$PN"1"64;
%"Q_RES"
"1","(-10300,6675)","2","pure_quanta","I43";
;
LOCATION"R6025"
$SEC"1"
CDS_SEC"1"
VALUE"0"
CDS_LIB"pure_quanta"
BOM_COST"MEM"
WATTAGE"1/16W"
MATERIAL"CHIP"
TOLERANCE"5%"
PACK_TYPE"0402LF"
PART_NUMBER"CS00002JB13";
"B"
$PN"2"32;
"A"
$PN"1"31;
%"Q_RES"
"1","(-9525,5125)","0","pure_quanta","I50";
;
LOCATION"R3254"
$SEC"1"
CDS_SEC"1"
MATERIAL"EMPTY"
PACK_TYPE"0402LF"
WATTAGE"1/16W"
VALUE"0"
TOLERANCE"5%"
CDS_LIB"pure_quanta"
PART_NUMBER"CS00002JB13";
"B"
$PN"2"174;
"A"
$PN"1"115;
%"UNIVERSAL_GND"
"1","(-8500,6475)","0","pure_quanta_power","I58";
;
CDS_LIB"pure_quanta_power"
HDL_POWER"GND";
"A"7;
%"Q_RES"
"1","(-14950,6725)","0","pure_quanta","I60";
;
LOCATION"R2415"
$SEC"1"
CDS_SEC"1"
MATERIAL"CHIP"
TOLERANCE"1%"
VALUE"33.2"
WATTAGE"1/16W"
PACK_TYPE"0402LF"
CDS_LIB"pure_quanta"
PART_NUMBER"CS03322FB03";
"B"
$PN"2"167;
"A"
$PN"1"11;
%"Q_RES"
"1","(-14950,7025)","0","pure_quanta","I85";
;
LOCATION"R2414"
$SEC"1"
CDS_SEC"1"
VALUE"33.2"
TOLERANCE"1%"
MATERIAL"CHIP"
PACK_TYPE"0402LF"
WATTAGE"1/16W"
CDS_LIB"pure_quanta"
PART_NUMBER"CS03322FB03";
"B"
$PN"2"44;
"A"
$PN"1"148;
%"Q_RES"
"1","(-14950,7075)","0","pure_quanta","I86";
;
LOCATION"R2413"
$SEC"1"
CDS_SEC"1"
VALUE"33.2"
TOLERANCE"1%"
MATERIAL"CHIP"
PACK_TYPE"0402LF"
WATTAGE"1/16W"
CDS_LIB"pure_quanta"
PART_NUMBER"CS03322FB03";
"B"
$PN"2"43;
"A"
$PN"1"140;
%"Q_RES"
"1","(-14925,7325)","0","pure_quanta","I87";
;
LOCATION"R4509"
$SEC"1"
CDS_SEC"1"
TOLERANCE"1%"
VALUE"33.2"
MATERIAL"CHIP"
CDS_LIB"pure_quanta"
PACK_TYPE"0402LF"
WATTAGE"1/16W"
PART_NUMBER"CS03322FB03";
"B"
$PN"2"131;
"A"
$PN"1"149;
%"Q_RES"
"1","(-14925,7375)","0","pure_quanta","I88";
;
LOCATION"R4508"
$SEC"1"
CDS_SEC"1"
TOLERANCE"1%"
MATERIAL"CHIP"
VALUE"33.2"
CDS_LIB"pure_quanta"
PACK_TYPE"0402LF"
WATTAGE"1/16W"
PART_NUMBER"CS03322FB03";
"B"
$PN"2"132;
"A"
$PN"1"135;
%"Q_RES"
"1","(-14925,8125)","0","pure_quanta","I96";
;
LOCATION"R3858"
$SEC"1"
CDS_SEC"1"
MATERIAL"CHIP"
VALUE"33.2"
TOLERANCE"1%"
CDS_LIB"pure_quanta"
PACK_TYPE"0402LF"
WATTAGE"1/16W"
PART_NUMBER"CS03322FB03";
"B"
$PN"2"111;
"A"
$PN"1"138;
%"Q_RES"
"1","(-14925,8175)","0","pure_quanta","I97";
;
LOCATION"R2425"
$SEC"1"
CDS_SEC"1"
TOLERANCE"1%"
MATERIAL"CHIP"
VALUE"33.2"
WATTAGE"1/16W"
PACK_TYPE"0402LF"
CDS_LIB"pure_quanta"
PART_NUMBER"CS03322FB03";
"B"
$PN"2"112;
"A"
$PN"1"147;
%"Q_RES"
"1","(-14925,8475)","0","pure_quanta","I98";
;
LOCATION"R2421"
$SEC"1"
CDS_SEC"1"
TOLERANCE"1%"
MATERIAL"CHIP"
VALUE"33.2"
CDS_LIB"pure_quanta"
PACK_TYPE"0402LF"
WATTAGE"1/16W"
PART_NUMBER"CS03322FB03";
"B"
$PN"2"157;
"A"
$PN"1"126;
END.
